FILE_TYPE = CONNECTIVITY;
{Allegro Design Entry HDL 17.4-2019 S026 (4007227) 1/17/2022}
"PAGE_NUMBER" = 421;
0"NC";
1"GND\g";
2"GND\g";
3"GND\g";
4"GND\g";
5"SMB_RT_CPU0_P2_ROM_R_SDA";
6"SMB_RT_CPU0_P2_ROM_SDA";
7"SMB_RT_CPU0_P2_ROM_R_SCL";
8"SMB_RT_CPU0_P2_ROM_SCL";
9"U16_E2";
10"P1V8_CPU0_RT_1D\g";
%"Q_RES"
"2","(-4100,5450)","0","pure_quanta","I18";
;
LOCATION"R1085"
$SEC"1"
CDS_SEC"1"
VALUE"1K"
TOLERANCE"1%"
WATTAGE"1/20W"
MATERIAL"CHIP"
PACK_TYPE"0201LF"
CDS_LIB"pure_quanta"
PART_NUMBER"CS21001FE07";
"A"
$PN"1"9;
"B"
$PN"2"1;
%"UNIVERSAL_GND"
"1","(-4100,5025)","0","pure_quanta_power","I19";
;
CDS_LIB"pure_quanta_power"
HDL_POWER"GND";
"A"1;
%"UNIVERSAL_GND"
"1","(-4250,5375)","0","pure_quanta_power","I20";
;
CDS_LIB"pure_quanta_power"
HDL_POWER"GND";
"A"2;
%"UNIVERSAL_GND"
"1","(-5250,5675)","7","pure_quanta_power","I21";
;
CDS_LIB"pure_quanta_power"
HDL_POWER"GND";
"A"3;
%"P1V0"
"1","(-5250,6500)","0","pure_quanta_power","I22";
;
HDL_POWER"P1V8_CPU0_RT_1D"
CDS_LIB"pure_quanta_power";
"A"10;
%"Q_CAP"
"1","(-5550,6150)","0","pure_quanta","I23";
;
LOCATION"C989"
$SEC"1"
CDS_SEC"1"
PACK_TYPE"C0201"
MATERIAL"X7S"
VOLTAGE"10V"
TOLERANCE"10%"
VALUE"0.1UF"
CDS_LIB"pure_quanta"
PART_NUMBER"CH4102K6E00";
"B"
$PN"2"4;
"A"
$PN"1"10;
%"UNIVERSAL_GND"
"1","(-5550,5875)","0","pure_quanta_power","I24";
;
CDS_LIB"pure_quanta_power"
HDL_POWER"GND";
"A"4;
%"Q_RES"
"1","(-6200,5625)","0","pure_quanta","I3";
;
LOCATION"R682"
$SEC"1"
CDS_SEC"1"
MATERIAL"CHIP"
PACK_TYPE"0201LF"
WATTAGE"1/20W"
VALUE"33.2"
TOLERANCE"1%"
CDS_LIB"pure_quanta"
PART_NUMBER"CS03321FE09";
"B"
$PN"2"8;
"A"
$PN"1"7;
%"Q_RES"
"1","(-6200,5575)","0","pure_quanta","I4";
;
LOCATION"R683"
$SEC"1"
CDS_SEC"1"
CDS_LIB"pure_quanta"
MATERIAL"CHIP"
WATTAGE"1/20W"
PACK_TYPE"0201LF"
VALUE"33.2"
TOLERANCE"1%"
PART_NUMBER"CS03321FE09";
"B"
$PN"2"6;
"A"
$PN"1"5;
%"M24M02DRMN6TP"
"1","(-4775,5650)","0","pure_quanta","I5";
;
LOCATION"U16"
$SEC"1"
CDS_SEC"1"
VALUE"M24M02-DRMN6TP"
PART_TYPE"SMLF"
MATERIAL"IC"
CDS_LIB"pure_quanta"
CDS_LMAN_SYM_OUTLINE"-175,125,175,-125"
NEEDS_NO_SIZE"TRUE"
PART_NUMBER"AKE33Z00600";
"DU1"
$PN"1"0;
"DU2"
$PN"2"0;
"E2"
$PN"3"9;
"VSS"
$PN"4"2;
"SDA"
$PN"5"6;
"SCL"
$PN"6"8;
"WC_N \B"
$PN"7"3;
"VCC"
$PN"8"10;
END.
